FILE_TYPE = MULTI_PHYS_TABLE;
PART 'SCONN120_A28699018'
{==================================================================================================================================================================================}
:PACK_TYPE | MATERIAL | PART_NUMBER     = EnvComp | PART_NUMBER  | JEDEC_TYPE           | CLASS | DESCRIPTION                      | HEIGHT     | COMPONENT_TYPE | LPID   | SPEED_URL | Status |RPL| AML | Bus_Unit | Days ;
{==================================================================================================================================================================================}
'SM'       | 'SCONN'  | 'A28699-018'(!) = ''      | 'A28699-018' | 'SCONN120_A28699018' | 'IO'  | 'CONN,BTB,120P,RCP,VT,0MM,.8MM'  | '0.472 IN' | 'SMTCONN'      | '3924' | 'http://speed.intel.com:8081/speed/module/pdm/item/pdm_item_detail_direct.asp?item_cde=A28699-018&item_rev=01&url_param=unused' | '' | '' | '' | '' | '' 
'SM'       | 'EMPTY'  | 'A28699-018'(!) = ''      | 'A28699-018' | 'SCONN120_A28699018' | 'IO'  | 'CONN,BTB,120P,RCP,VT,0MM,.8MM'  | '0.472 IN' | 'SMTCONN'      | '3924' | 'http://speed.intel.com:8081/speed/module/pdm/item/pdm_item_detail_direct.asp?item_cde=A28699-018&item_rev=01&url_param=unused' | '' | '' | '' | '' | '' 
END_PART
END.
